# T6G (Grand Teton) — schematic netlist excerpt (pin names and nets, part order shuffled) for the footprints in the layout excerpt that follows; sources: Cadence DE-HDL packaged netlist, KiCad conversion of 04192023_DAF0TMB3IC0_F0TG_MB_C_brd_V02_OCP.brd

R622  Q_RES  0 5% CHIP  pkg 0201LF  page 353 : A = CLK_100M_RETIMER_CPU1_P3_R_DN ; B = CLK_100M_RETIMER_CPU1_P3_DN

PR6002  Q_SP_RES4P  0.003 1% CHIP  pkg R2512_4PXM  page 266
  \1a\  = P12V_PSU
  \1b\  = P12V_HSC_SENSE1_P
  \2a\  = P12V_MAIN_R_0
  \2b\  = P12V_HSC_SENSE1_N

C2445  Q_CAP  22UF 4V 20% X6S  pkg C0402  page 74 : A = PVDDCR_SOC_P1 ; B = GND

(kicad_pcb
	(version 20260206)
	(generator "pcbnew")
	(generator_version "10.0")
	(general
		(thickness 1.6)
		(legacy_teardrops no)
	)
	(paper "A4")
	(title_block
		(title "04192023_DAF0TMB3IC0_F0TG_MB_C_brd_V02_OCP.brd")
		(comment 1 "Grand Teton / footprints 630-632 of 8354")
	)
	(layers
		(0 "F.Cu" signal "TOP")
		(4 "In1.Cu" signal "GND")
		(6 "In2.Cu" signal "IN1")
		(8 "In3.Cu" signal "GND1")
		(10 "In4.Cu" signal "IN2")
		(12 "In5.Cu" signal "GND2")
		(14 "In6.Cu" signal "IN3")
		(16 "In7.Cu" signal "GND3")
		(18 "In8.Cu" signal "VCC")
		(20 "In9.Cu" signal "VCC1")
		(22 "In10.Cu" signal "GND4")
		(24 "In11.Cu" signal "IN4")
		(26 "In12.Cu" signal "GND5")
		(28 "In13.Cu" signal "IN5")
		(30 "In14.Cu" signal "GND6")
		(32 "In15.Cu" signal "IN6")
		(34 "In16.Cu" signal "GND7")
		(2 "B.Cu" signal "BOTTOM")
		(9 "F.Adhes" user "F.Adhesive")
		(11 "B.Adhes" user "B.Adhesive")
		(13 "F.Paste" user "Package Geometry/Pastemask Top")
		(15 "B.Paste" user "Package Geometry/Pastemask Bottom")
		(5 "F.SilkS" user "Ref Des/Silkscreen Top")
		(7 "B.SilkS" user "Ref Des/Silkscreen Bottom")
		(1 "F.Mask" user "Board Geometry/Soldermask Top")
		(3 "B.Mask" user "Board Geometry/Soldermask Bottom")
		(17 "Dwgs.User" user "User.Drawings")
		(19 "Cmts.User" user "User.Comments")
		(21 "Eco1.User" user "User.Eco1")
		(23 "Eco2.User" user "User.Eco2")
		(25 "Edge.Cuts" user "Board Geometry/Outline")
		(27 "Margin" user)
		(31 "F.CrtYd" user "Package Geometry/Place Bound Top")
		(29 "B.CrtYd" user "Package Geometry/Place Bound Bottom")
		(35 "F.Fab" user "Ref Des/Assembly Top")
		(33 "B.Fab" user "Ref Des/Assembly Bottom")
	)
	(footprint ""
		(layer "F.Cu")
		(at 108.625894 -256.012442 90)
		(property "Reference" "C2445"
			(at 0 0 90)
			(layer "F.SilkS")
			(hide yes)
			(effects
				(font
					(size 1.27 1.27)
				)
			)
		)
		(property "Value" ""
			(at 0 0 90)
			(layer "F.Fab")
			(effects
				(font
					(size 1.27 1.27)
				)
			)
		)
		(duplicate_pad_numbers_are_jumpers no)
		(fp_line
			(start 0.7874 -0.4064)
			(end 0.7874 0.4064)
			(stroke
				(width 0.1524)
				(type default)
			)
			(layer "F.SilkS")
		)
		(fp_line
			(start -0.7874 -0.4064)
			(end 0.7874 -0.4064)
			(stroke
				(width 0.1524)
				(type default)
			)
			(layer "F.SilkS")
		)
		(fp_line
			(start 0.7874 0.4064)
			(end -0.7874 0.4064)
			(stroke
				(width 0.1524)
				(type default)
			)
			(layer "F.SilkS")
		)
		(fp_line
			(start -0.7874 0.4064)
			(end -0.7874 -0.4064)
			(stroke
				(width 0.1524)
				(type default)
			)
			(layer "F.SilkS")
		)
		(fp_line
			(start -0.12065 -0.305054)
			(end -0.12065 -0.2794)
			(stroke
				(width 0.1)
				(type default)
			)
			(layer "F.Fab")
		)
		(fp_line
			(start -0.67945 -0.305054)
			(end -0.12065 -0.305054)
			(stroke
				(width 0.1)
				(type default)
			)
			(layer "F.Fab")
		)
		(fp_line
			(start 0.67945 -0.3048)
			(end 0.67945 0.3048)
			(stroke
				(width 0.1)
				(type default)
			)
			(layer "F.Fab")
		)
		(fp_line
			(start 0.12065 -0.3048)
			(end 0.67945 -0.3048)
			(stroke
				(width 0.1)
				(type default)
			)
			(layer "F.Fab")
		)
		(fp_line
			(start 0.12065 -0.2794)
			(end 0.12065 -0.3048)
			(stroke
				(width 0.1)
				(type default)
			)
			(layer "F.Fab")
		)
		(fp_line
			(start -0.12065 -0.2794)
			(end 0.12065 -0.2794)
			(stroke
				(width 0.1)
				(type default)
			)
			(layer "F.Fab")
		)
		(fp_line
			(start 0.120396 0.2794)
			(end -0.12065 0.2794)
			(stroke
				(width 0.1)
				(type default)
			)
			(layer "F.Fab")
		)
		(fp_line
			(start -0.12065 0.2794)
			(end -0.12065 0.3048)
			(stroke
				(width 0.1)
				(type default)
			)
			(layer "F.Fab")
		)
		(fp_line
			(start 0.67945 0.3048)
			(end 0.120396 0.3048)
			(stroke
				(width 0.1)
				(type default)
			)
			(layer "F.Fab")
		)
		(fp_line
			(start 0.120396 0.3048)
			(end 0.120396 0.2794)
			(stroke
				(width 0.1)
				(type default)
			)
			(layer "F.Fab")
		)
		(fp_line
			(start -0.12065 0.3048)
			(end -0.67945 0.3048)
			(stroke
				(width 0.1)
				(type default)
			)
			(layer "F.Fab")
		)
		(fp_line
			(start -0.67945 0.3048)
			(end -0.67945 -0.305054)
			(stroke
				(width 0.1)
				(type default)
			)
			(layer "F.Fab")
		)
		(pad "1" smd circle
			(at -0.40005 0 90)
			(size 0 0)
			(layers "F.Cu" "F.Mask" "F.Paste")
			(net "PVDDCR_SOC_P1")
		)
		(pad "2" smd circle
			(at 0.40005 0 90)
			(size 0 0)
			(layers "F.Cu" "F.Mask" "F.Paste")
			(net "GND")
		)
	)
	(footprint ""
		(layer "F.Cu")
		(at 277.224236 -393.899136 -90)
		(property "Reference" "PR6002"
			(at 0.449072 -2.98958 90)
			(unlocked yes)
			(layer "F.SilkS")
			(effects
				(font
					(size 0.7874 0.5842)
					(thickness 0.1524)
				)
				(justify left)
			)
		)
		(property "Value" ""
			(at 0 0 270)
			(layer "F.Fab")
			(effects
				(font
					(size 1.27 1.27)
				)
			)
		)
		(duplicate_pad_numbers_are_jumpers no)
		(fp_line
			(start -4.13258 2.1336)
			(end 4.13258 2.1336)
			(stroke
				(width 0.1524)
				(type default)
			)
			(layer "F.SilkS")
		)
		(fp_line
			(start 4.13258 2.1336)
			(end 4.13258 -2.1336)
			(stroke
				(width 0.1524)
				(type default)
			)
			(layer "F.SilkS")
		)
		(fp_line
			(start -4.13258 -2.1336)
			(end -4.13258 2.1336)
			(stroke
				(width 0.1524)
				(type default)
			)
			(layer "F.SilkS")
		)
		(fp_line
			(start 4.13258 -2.1336)
			(end -4.13258 -2.1336)
			(stroke
				(width 0.1524)
				(type default)
			)
			(layer "F.SilkS")
		)
		(fp_line
			(start -3.350006 1.700022)
			(end 3.350006 1.700022)
			(stroke
				(width 0.1)
				(type default)
			)
			(layer "F.Fab")
		)
		(fp_line
			(start 3.350006 1.700022)
			(end 3.350006 -1.700022)
			(stroke
				(width 0.1)
				(type default)
			)
			(layer "F.Fab")
		)
		(fp_line
			(start -3.350006 -1.700022)
			(end -3.350006 1.700022)
			(stroke
				(width 0.1)
				(type default)
			)
			(layer "F.Fab")
		)
		(fp_line
			(start 3.350006 -1.700022)
			(end -3.350006 -1.700022)
			(stroke
				(width 0.1)
				(type default)
			)
			(layer "F.Fab")
		)
		(pad "1A" smd rect
			(at -3.024886 0 270)
			(size 1.9558 4.0132)
			(layers "F.Cu" "F.Mask" "F.Paste")
			(net "P12V_PSU")
		)
		(pad "1B" smd rect
			(at -2.173986 0 270)
			(size 0.254 0.508)
			(layers "F.Cu" "F.Mask" "F.Paste")
			(net "P12V_HSC_SENSE1_P")
		)
		(pad "2A" smd rect
			(at 3.024886 0 270)
			(size 1.9558 4.0132)
			(layers "F.Cu" "F.Mask" "F.Paste")
			(net "P12V_MAIN_R_0")
		)
		(pad "2B" smd rect
			(at 2.173986 0 270)
			(size 0.254 0.508)
			(layers "F.Cu" "F.Mask" "F.Paste")
			(net "P12V_HSC_SENSE1_N")
		)
	)
	(footprint ""
		(layer "F.Cu")
		(at 109.627924 -386.951474)
		(property "Reference" "R622"
			(at 0 0 0)
			(layer "F.SilkS")
			(hide yes)
			(effects
				(font
					(size 1.27 1.27)
				)
			)
		)
		(property "Value" ""
			(at 0 0 0)
			(layer "F.Fab")
			(effects
				(font
					(size 1.27 1.27)
				)
			)
		)
		(duplicate_pad_numbers_are_jumpers no)
		(fp_line
			(start -0.32512 -0.175006)
			(end 0.32512 -0.175006)
			(stroke
				(width 0.1)
				(type default)
			)
			(layer "F.Fab")
		)
		(fp_line
			(start -0.32512 0.175006)
			(end -0.32512 -0.175006)
			(stroke
				(width 0.1)
				(type default)
			)
			(layer "F.Fab")
		)
		(fp_line
			(start 0.32512 -0.175006)
			(end 0.32512 0.175006)
			(stroke
				(width 0.1)
				(type default)
			)
			(layer "F.Fab")
		)
		(fp_line
			(start 0.32512 0.175006)
			(end -0.32512 0.175006)
			(stroke
				(width 0.1)
				(type default)
			)
			(layer "F.Fab")
		)
		(pad "1" smd rect
			(at -0.2667 0)
			(size 0.3048 0.381)
			(layers "F.Cu" "F.Mask" "F.Paste")
			(net "CLK_100M_RETIMER_CPU1_P3_R_DN")
		)
		(pad "2" smd rect
			(at 0.2667 0 180)
			(size 0.3048 0.381)
			(layers "F.Cu" "F.Mask" "F.Paste")
			(net "CLK_100M_RETIMER_CPU1_P3_DN")
		)
	)
)
